(kicad_pcb
	(version 20260206)
	(generator "pcbnew")
	(generator_version "10.0")
	(general
		(thickness 1.6)
		(legacy_teardrops no)
	)
	(paper "A4")
	(title_block
		(title "03242023_DA0F0TMBIJ0_F0T_Motherboard_J_brd_V01_OCP.brd")
		(comment 1 "Grand Teton / footprints 2796-2801 of 6105")
	)
	(layers
		(0 "F.Cu" signal "TOP")
		(4 "In1.Cu" signal "GND")
		(6 "In2.Cu" signal "IN1")
		(8 "In3.Cu" signal "GND1")
		(10 "In4.Cu" signal "IN2")
		(12 "In5.Cu" signal "GND2")
		(14 "In6.Cu" signal "IN3")
		(16 "In7.Cu" signal "GND3")
		(18 "In8.Cu" signal "VCC")
		(20 "In9.Cu" signal "VCC1")
		(22 "In10.Cu" signal "GND4")
		(24 "In11.Cu" signal "IN4")
		(26 "In12.Cu" signal "GND5")
		(28 "In13.Cu" signal "IN5")
		(30 "In14.Cu" signal "GND6")
		(32 "In15.Cu" signal "IN6")
		(34 "In16.Cu" signal "GND7")
		(2 "B.Cu" signal "BOTTOM")
		(9 "F.Adhes" user "F.Adhesive")
		(11 "B.Adhes" user "B.Adhesive")
		(13 "F.Paste" user "Package Geometry/Pastemask Top")
		(15 "B.Paste" user "Package Geometry/Pastemask Bottom")
		(5 "F.SilkS" user "Ref Des/Silkscreen Top")
		(7 "B.SilkS" user "Ref Des/Silkscreen Bottom")
		(1 "F.Mask" user "Board Geometry/Soldermask Top")
		(3 "B.Mask" user "Board Geometry/Soldermask Bottom")
		(17 "Dwgs.User" user "User.Drawings")
		(19 "Cmts.User" user "User.Comments")
		(21 "Eco1.User" user "User.Eco1")
		(23 "Eco2.User" user "User.Eco2")
		(25 "Edge.Cuts" user "Board Geometry/Outline")
		(27 "Margin" user)
		(31 "F.CrtYd" user "Package Geometry/Place Bound Top")
		(29 "B.CrtYd" user "Package Geometry/Place Bound Bottom")
		(35 "F.Fab" user "Ref Des/Assembly Top")
		(33 "B.Fab" user "Ref Des/Assembly Bottom")
	)
	(footprint ""
		(layer "F.Cu")
		(at 406.124664 -359.579926 180)
		(property "Reference" "R1232"
			(at 0 0 180)
			(layer "F.SilkS")
			(hide yes)
			(effects
				(font
					(size 1.27 1.27)
				)
			)
		)
		(property "Value" ""
			(at 0 0 180)
			(layer "F.Fab")
			(effects
				(font
					(size 1.27 1.27)
				)
			)
		)
		(duplicate_pad_numbers_are_jumpers no)
		(fp_line
			(start 0.7874 0.4064)
			(end -0.7874 0.4064)
			(stroke
				(width 0.1524)
				(type default)
			)
			(layer "F.SilkS")
		)
		(fp_line
			(start 0.7874 -0.4064)
			(end 0.7874 0.4064)
			(stroke
				(width 0.1524)
				(type default)
			)
			(layer "F.SilkS")
		)
		(fp_line
			(start -0.7874 0.4064)
			(end -0.7874 -0.4064)
			(stroke
				(width 0.1524)
				(type default)
			)
			(layer "F.SilkS")
		)
		(fp_line
			(start -0.7874 -0.4064)
			(end 0.7874 -0.4064)
			(stroke
				(width 0.1524)
				(type default)
			)
			(layer "F.SilkS")
		)
		(fp_line
			(start 0.67945 0.3048)
			(end 0.120396 0.3048)
			(stroke
				(width 0.1)
				(type default)
			)
			(layer "F.Fab")
		)
		(fp_line
			(start 0.67945 -0.3048)
			(end 0.67945 0.3048)
			(stroke
				(width 0.1)
				(type default)
			)
			(layer "F.Fab")
		)
		(fp_line
			(start 0.12065 -0.2794)
			(end 0.12065 -0.3048)
			(stroke
				(width 0.1)
				(type default)
			)
			(layer "F.Fab")
		)
		(fp_line
			(start 0.12065 -0.3048)
			(end 0.67945 -0.3048)
			(stroke
				(width 0.1)
				(type default)
			)
			(layer "F.Fab")
		)
		(fp_line
			(start 0.120396 0.3048)
			(end 0.120396 0.2794)
			(stroke
				(width 0.1)
				(type default)
			)
			(layer "F.Fab")
		)
		(fp_line
			(start 0.120396 0.2794)
			(end -0.12065 0.2794)
			(stroke
				(width 0.1)
				(type default)
			)
			(layer "F.Fab")
		)
		(fp_line
			(start -0.12065 0.3048)
			(end -0.67945 0.3048)
			(stroke
				(width 0.1)
				(type default)
			)
			(layer "F.Fab")
		)
		(fp_line
			(start -0.12065 0.2794)
			(end -0.12065 0.3048)
			(stroke
				(width 0.1)
				(type default)
			)
			(layer "F.Fab")
		)
		(fp_line
			(start -0.12065 -0.2794)
			(end 0.12065 -0.2794)
			(stroke
				(width 0.1)
				(type default)
			)
			(layer "F.Fab")
		)
		(fp_line
			(start -0.12065 -0.305054)
			(end -0.12065 -0.2794)
			(stroke
				(width 0.1)
				(type default)
			)
			(layer "F.Fab")
		)
		(fp_line
			(start -0.67945 0.3048)
			(end -0.67945 -0.305054)
			(stroke
				(width 0.1)
				(type default)
			)
			(layer "F.Fab")
		)
		(fp_line
			(start -0.67945 -0.305054)
			(end -0.12065 -0.305054)
			(stroke
				(width 0.1)
				(type default)
			)
			(layer "F.Fab")
		)
		(pad "1" smd circle
			(at -0.40005 0 180)
			(size 0 0)
			(layers "F.Cu" "F.Mask" "F.Paste")
			(net "PVNN_TERM_CPU0")
		)
		(pad "2" smd circle
			(at 0.40005 0 180)
			(size 0 0)
			(layers "F.Cu" "F.Mask" "F.Paste")
			(net "PUD_XTAL_CPU0_MODE0")
		)
	)
	(footprint ""
		(layer "F.Cu")
		(at 261.436612 -130.600704 180)
		(property "Reference" "R4496"
			(at 0 0 180)
			(layer "F.SilkS")
			(hide yes)
			(effects
				(font
					(size 1.27 1.27)
				)
			)
		)
		(property "Value" ""
			(at 0 0 180)
			(layer "F.Fab")
			(effects
				(font
					(size 1.27 1.27)
				)
			)
		)
		(duplicate_pad_numbers_are_jumpers no)
		(fp_line
			(start 0.7874 0.4064)
			(end -0.7874 0.4064)
			(stroke
				(width 0.1524)
				(type default)
			)
			(layer "F.SilkS")
		)
		(fp_line
			(start 0.7874 -0.4064)
			(end 0.7874 0.4064)
			(stroke
				(width 0.1524)
				(type default)
			)
			(layer "F.SilkS")
		)
		(fp_line
			(start -0.7874 0.4064)
			(end -0.7874 -0.4064)
			(stroke
				(width 0.1524)
				(type default)
			)
			(layer "F.SilkS")
		)
		(fp_line
			(start -0.7874 -0.4064)
			(end 0.7874 -0.4064)
			(stroke
				(width 0.1524)
				(type default)
			)
			(layer "F.SilkS")
		)
		(fp_line
			(start 0.67945 0.3048)
			(end 0.120396 0.3048)
			(stroke
				(width 0.1)
				(type default)
			)
			(layer "F.Fab")
		)
		(fp_line
			(start 0.67945 -0.3048)
			(end 0.67945 0.3048)
			(stroke
				(width 0.1)
				(type default)
			)
			(layer "F.Fab")
		)
		(fp_line
			(start 0.12065 -0.2794)
			(end 0.12065 -0.3048)
			(stroke
				(width 0.1)
				(type default)
			)
			(layer "F.Fab")
		)
		(fp_line
			(start 0.12065 -0.3048)
			(end 0.67945 -0.3048)
			(stroke
				(width 0.1)
				(type default)
			)
			(layer "F.Fab")
		)
		(fp_line
			(start 0.120396 0.3048)
			(end 0.120396 0.2794)
			(stroke
				(width 0.1)
				(type default)
			)
			(layer "F.Fab")
		)
		(fp_line
			(start 0.120396 0.2794)
			(end -0.12065 0.2794)
			(stroke
				(width 0.1)
				(type default)
			)
			(layer "F.Fab")
		)
		(fp_line
			(start -0.12065 0.3048)
			(end -0.67945 0.3048)
			(stroke
				(width 0.1)
				(type default)
			)
			(layer "F.Fab")
		)
		(fp_line
			(start -0.12065 0.2794)
			(end -0.12065 0.3048)
			(stroke
				(width 0.1)
				(type default)
			)
			(layer "F.Fab")
		)
		(fp_line
			(start -0.12065 -0.2794)
			(end 0.12065 -0.2794)
			(stroke
				(width 0.1)
				(type default)
			)
			(layer "F.Fab")
		)
		(fp_line
			(start -0.12065 -0.305054)
			(end -0.12065 -0.2794)
			(stroke
				(width 0.1)
				(type default)
			)
			(layer "F.Fab")
		)
		(fp_line
			(start -0.67945 0.3048)
			(end -0.67945 -0.305054)
			(stroke
				(width 0.1)
				(type default)
			)
			(layer "F.Fab")
		)
		(fp_line
			(start -0.67945 -0.305054)
			(end -0.12065 -0.305054)
			(stroke
				(width 0.1)
				(type default)
			)
			(layer "F.Fab")
		)
		(pad "1" smd circle
			(at -0.40005 0 180)
			(size 0 0)
			(layers "F.Cu" "F.Mask" "F.Paste")
			(net "SMB_HOST_CLK_BUF_ISO_3V3AUX_SCL")
		)
		(pad "2" smd circle
			(at 0.40005 0 180)
			(size 0 0)
			(layers "F.Cu" "F.Mask" "F.Paste")
			(net "SMB_HOST_DB2000_3V3AUX_SCL")
		)
	)
	(footprint ""
		(layer "F.Cu")
		(at 28.081732 -403.695408)
		(property "Reference" "Q96"
			(at 1.97358 1.620012 0)
			(unlocked yes)
			(layer "F.SilkS")
			(effects
				(font
					(size 0.7874 0.5842)
					(thickness 0.1524)
				)
				(justify left)
			)
		)
		(property "Value" ""
			(at 0 0 0)
			(layer "F.Fab")
			(effects
				(font
					(size 1.27 1.27)
				)
			)
		)
		(duplicate_pad_numbers_are_jumpers no)
		(fp_line
			(start -1.332738 -1.100074)
			(end -0.4826 -1.100074)
			(stroke
				(width 0.1524)
				(type default)
			)
			(layer "F.SilkS")
		)
		(fp_line
			(start -1.332738 1.100074)
			(end -1.332738 -1.100074)
			(stroke
				(width 0.1524)
				(type default)
			)
			(layer "F.SilkS")
		)
		(fp_line
			(start -0.4826 -1.100074)
			(end 0 -0.541274)
			(stroke
				(width 0.1524)
				(type default)
			)
			(layer "F.SilkS")
		)
		(fp_line
			(start 0 -0.541274)
			(end 0.4826 -1.100074)
			(stroke
				(width 0.1524)
				(type default)
			)
			(layer "F.SilkS")
		)
		(fp_line
			(start 0.4826 -1.100074)
			(end 1.332738 -1.100074)
			(stroke
				(width 0.1524)
				(type default)
			)
			(layer "F.SilkS")
		)
		(fp_line
			(start 1.332738 -1.100074)
			(end 1.332738 1.100074)
			(stroke
				(width 0.1524)
				(type default)
			)
			(layer "F.SilkS")
		)
		(fp_line
			(start 1.332738 1.100074)
			(end -1.332738 1.100074)
			(stroke
				(width 0.1524)
				(type default)
			)
			(layer "F.SilkS")
		)
		(fp_poly
			(pts
				(xy -1.848612 -1.41478) (xy -1.600454 -0.670306) (xy -2.344928 -0.918464)
			)
			(stroke
				(width 0)
				(type default)
			)
			(fill yes)
			(layer "F.SilkS")
		)
		(fp_line
			(start -0.674878 -1.100074)
			(end 0.674878 -1.100074)
			(stroke
				(width 0.1)
				(type default)
			)
			(layer "F.Fab")
		)
		(fp_line
			(start -0.674878 1.100074)
			(end -0.674878 -1.100074)
			(stroke
				(width 0.1)
				(type default)
			)
			(layer "F.Fab")
		)
		(fp_line
			(start 0.674878 -1.100074)
			(end 0.674878 1.100074)
			(stroke
				(width 0.1)
				(type default)
			)
			(layer "F.Fab")
		)
		(fp_line
			(start 0.674878 1.100074)
			(end -0.674878 1.100074)
			(stroke
				(width 0.1)
				(type default)
			)
			(layer "F.Fab")
		)
		(fp_poly
			(pts
				(xy -2.2352 -0.298958) (xy -2.2352 -1.001014) (xy -1.533144 -0.649986)
			)
			(stroke
				(width 0)
				(type default)
			)
			(fill yes)
			(layer "F.Fab")
		)
		(pad "1" smd rect
			(at -0.94996 -0.649986 90)
			(size 0.4318 0.508)
			(layers "F.Cu" "F.Mask" "F.Paste")
			(net "GND")
		)
		(pad "2" smd rect
			(at -0.94996 0 90)
			(size 0.4318 0.508)
			(layers "F.Cu" "F.Mask" "F.Paste")
			(net "GPU_FPGA_READY")
		)
		(pad "3" smd rect
			(at -0.94996 0.649986 90)
			(size 0.4318 0.508)
			(layers "F.Cu" "F.Mask" "F.Paste")
			(net "GPU_FPGA_READY_ISO")
		)
		(pad "4" smd rect
			(at 0.94996 0.649986 90)
			(size 0.4318 0.508)
			(layers "F.Cu" "F.Mask" "F.Paste")
			(net "GND")
		)
		(pad "5" smd rect
			(at 0.94996 0 90)
			(size 0.4318 0.508)
			(layers "F.Cu" "F.Mask" "F.Paste")
			(net "GPU_FPGA_READY_N")
		)
		(pad "6" smd rect
			(at 0.94996 -0.649986 90)
			(size 0.4318 0.508)
			(layers "F.Cu" "F.Mask" "F.Paste")
			(net "GPU_FPGA_READY_N")
		)
	)
	(footprint ""
		(layer "F.Cu")
		(at 189.28588 -130.266948 -90)
		(property "Reference" "R286"
			(at 0 0 270)
			(layer "F.SilkS")
			(hide yes)
			(effects
				(font
					(size 1.27 1.27)
				)
			)
		)
		(property "Value" ""
			(at 0 0 270)
			(layer "F.Fab")
			(effects
				(font
					(size 1.27 1.27)
				)
			)
		)
		(duplicate_pad_numbers_are_jumpers no)
		(fp_line
			(start -0.7874 0.4064)
			(end -0.7874 -0.4064)
			(stroke
				(width 0.1524)
				(type default)
			)
			(layer "F.SilkS")
		)
		(fp_line
			(start 0.7874 0.4064)
			(end -0.7874 0.4064)
			(stroke
				(width 0.1524)
				(type default)
			)
			(layer "F.SilkS")
		)
		(fp_line
			(start -0.7874 -0.4064)
			(end 0.7874 -0.4064)
			(stroke
				(width 0.1524)
				(type default)
			)
			(layer "F.SilkS")
		)
		(fp_line
			(start 0.7874 -0.4064)
			(end 0.7874 0.4064)
			(stroke
				(width 0.1524)
				(type default)
			)
			(layer "F.SilkS")
		)
		(fp_line
			(start -0.67945 0.3048)
			(end -0.67945 -0.305054)
			(stroke
				(width 0.1)
				(type default)
			)
			(layer "F.Fab")
		)
		(fp_line
			(start -0.12065 0.3048)
			(end -0.67945 0.3048)
			(stroke
				(width 0.1)
				(type default)
			)
			(layer "F.Fab")
		)
		(fp_line
			(start 0.120396 0.3048)
			(end 0.120396 0.2794)
			(stroke
				(width 0.1)
				(type default)
			)
			(layer "F.Fab")
		)
		(fp_line
			(start 0.67945 0.3048)
			(end 0.120396 0.3048)
			(stroke
				(width 0.1)
				(type default)
			)
			(layer "F.Fab")
		)
		(fp_line
			(start -0.12065 0.2794)
			(end -0.12065 0.3048)
			(stroke
				(width 0.1)
				(type default)
			)
			(layer "F.Fab")
		)
		(fp_line
			(start 0.120396 0.2794)
			(end -0.12065 0.2794)
			(stroke
				(width 0.1)
				(type default)
			)
			(layer "F.Fab")
		)
		(fp_line
			(start -0.12065 -0.2794)
			(end 0.12065 -0.2794)
			(stroke
				(width 0.1)
				(type default)
			)
			(layer "F.Fab")
		)
		(fp_line
			(start 0.12065 -0.2794)
			(end 0.12065 -0.3048)
			(stroke
				(width 0.1)
				(type default)
			)
			(layer "F.Fab")
		)
		(fp_line
			(start 0.12065 -0.3048)
			(end 0.67945 -0.3048)
			(stroke
				(width 0.1)
				(type default)
			)
			(layer "F.Fab")
		)
		(fp_line
			(start 0.67945 -0.3048)
			(end 0.67945 0.3048)
			(stroke
				(width 0.1)
				(type default)
			)
			(layer "F.Fab")
		)
		(fp_line
			(start -0.67945 -0.305054)
			(end -0.12065 -0.305054)
			(stroke
				(width 0.1)
				(type default)
			)
			(layer "F.Fab")
		)
		(fp_line
			(start -0.12065 -0.305054)
			(end -0.12065 -0.2794)
			(stroke
				(width 0.1)
				(type default)
			)
			(layer "F.Fab")
		)
		(pad "1" smd circle
			(at -0.40005 0 270)
			(size 0 0)
			(layers "F.Cu" "F.Mask" "F.Paste")
			(net "P3V3_AUX")
		)
		(pad "2" smd circle
			(at 0.40005 0 270)
			(size 0 0)
			(layers "F.Cu" "F.Mask" "F.Paste")
			(net "FM_CPU0_PROC_ID0")
		)
	)
	(footprint ""
		(layer "F.Cu")
		(at 58.490358 -408.517344 -90)
		(property "Reference" "C702"
			(at 0 0 270)
			(layer "F.SilkS")
			(hide yes)
			(effects
				(font
					(size 1.27 1.27)
				)
			)
		)
		(property "Value" ""
			(at 0 0 270)
			(layer "F.Fab")
			(effects
				(font
					(size 1.27 1.27)
				)
			)
		)
		(duplicate_pad_numbers_are_jumpers no)
		(fp_line
			(start -0.299974 0.150114)
			(end -0.299974 -0.150114)
			(stroke
				(width 0.1)
				(type default)
			)
			(layer "F.Fab")
		)
		(fp_line
			(start 0.299974 0.150114)
			(end -0.299974 0.150114)
			(stroke
				(width 0.1)
				(type default)
			)
			(layer "F.Fab")
		)
		(fp_line
			(start -0.299974 -0.150114)
			(end 0.299974 -0.150114)
			(stroke
				(width 0.1)
				(type default)
			)
			(layer "F.Fab")
		)
		(fp_line
			(start 0.299974 -0.150114)
			(end 0.299974 0.150114)
			(stroke
				(width 0.1)
				(type default)
			)
			(layer "F.Fab")
		)
		(pad "1" smd rect
			(at -0.2667 0 270)
			(size 0.3048 0.381)
			(layers "F.Cu" "F.Mask" "F.Paste")
			(net "P5E_CPU1_PE4_TX_C_DN<3>")
		)
		(pad "2" smd rect
			(at 0.2667 0 270)
			(size 0.3048 0.381)
			(layers "F.Cu" "F.Mask" "F.Paste")
			(net "P5E_CPU1_PE4_TX_DN<3>")
		)
	)
	(footprint ""
		(layer "F.Cu")
		(at 437.242966 -122.648726 180)
		(property "Reference" "PR370"
			(at 0 0 180)
			(layer "F.SilkS")
			(hide yes)
			(effects
				(font
					(size 1.27 1.27)
				)
			)
		)
		(property "Value" ""
			(at 0 0 180)
			(layer "F.Fab")
			(effects
				(font
					(size 1.27 1.27)
				)
			)
		)
		(duplicate_pad_numbers_are_jumpers no)
		(fp_line
			(start 0.7874 0.4064)
			(end -0.7874 0.4064)
			(stroke
				(width 0.1524)
				(type default)
			)
			(layer "F.SilkS")
		)
		(fp_line
			(start 0.7874 -0.4064)
			(end 0.7874 0.4064)
			(stroke
				(width 0.1524)
				(type default)
			)
			(layer "F.SilkS")
		)
		(fp_line
			(start -0.7874 0.4064)
			(end -0.7874 -0.4064)
			(stroke
				(width 0.1524)
				(type default)
			)
			(layer "F.SilkS")
		)
		(fp_line
			(start -0.7874 -0.4064)
			(end 0.7874 -0.4064)
			(stroke
				(width 0.1524)
				(type default)
			)
			(layer "F.SilkS")
		)
		(fp_line
			(start 0.67945 0.3048)
			(end 0.120396 0.3048)
			(stroke
				(width 0.1)
				(type default)
			)
			(layer "F.Fab")
		)
		(fp_line
			(start 0.67945 -0.3048)
			(end 0.67945 0.3048)
			(stroke
				(width 0.1)
				(type default)
			)
			(layer "F.Fab")
		)
		(fp_line
			(start 0.12065 -0.2794)
			(end 0.12065 -0.3048)
			(stroke
				(width 0.1)
				(type default)
			)
			(layer "F.Fab")
		)
		(fp_line
			(start 0.12065 -0.3048)
			(end 0.67945 -0.3048)
			(stroke
				(width 0.1)
				(type default)
			)
			(layer "F.Fab")
		)
		(fp_line
			(start 0.120396 0.3048)
			(end 0.120396 0.2794)
			(stroke
				(width 0.1)
				(type default)
			)
			(layer "F.Fab")
		)
		(fp_line
			(start 0.120396 0.2794)
			(end -0.12065 0.2794)
			(stroke
				(width 0.1)
				(type default)
			)
			(layer "F.Fab")
		)
		(fp_line
			(start -0.12065 0.3048)
			(end -0.67945 0.3048)
			(stroke
				(width 0.1)
				(type default)
			)
			(layer "F.Fab")
		)
		(fp_line
			(start -0.12065 0.2794)
			(end -0.12065 0.3048)
			(stroke
				(width 0.1)
				(type default)
			)
			(layer "F.Fab")
		)
		(fp_line
			(start -0.12065 -0.2794)
			(end 0.12065 -0.2794)
			(stroke
				(width 0.1)
				(type default)
			)
			(layer "F.Fab")
		)
		(fp_line
			(start -0.12065 -0.305054)
			(end -0.12065 -0.2794)
			(stroke
				(width 0.1)
				(type default)
			)
			(layer "F.Fab")
		)
		(fp_line
			(start -0.67945 0.3048)
			(end -0.67945 -0.305054)
			(stroke
				(width 0.1)
				(type default)
			)
			(layer "F.Fab")
		)
		(fp_line
			(start -0.67945 -0.305054)
			(end -0.12065 -0.305054)
			(stroke
				(width 0.1)
				(type default)
			)
			(layer "F.Fab")
		)
		(pad "1" smd circle
			(at -0.40005 0 180)
			(size 0 0)
			(layers "F.Cu" "F.Mask" "F.Paste")
			(net "P3V3_AUX")
		)
		(pad "2" smd circle
			(at 0.40005 0 180)
			(size 0 0)
			(layers "F.Cu" "F.Mask" "F.Paste")
			(net "PVCCD_HV_CPU0_PIN_ALT")
		)
	)
)
